(kicad_pcb
	(version 20260206)
	(generator "pcbnew")
	(generator_version "10.0")
	(general
		(thickness 1.6)
		(legacy_teardrops no)
	)
	(paper "A4")
	(title_block
		(title "01162023_DA0F0TEBIF0_F0T_Expander_BD_F_brd_V02_OCP.brd")
		(comment 1 "Grand Teton / footprints 8094-8102 of 9728")
	)
	(layers
		(0 "F.Cu" signal "TOP")
		(4 "In1.Cu" signal "GND")
		(6 "In2.Cu" signal "VCC")
		(8 "In3.Cu" signal "VCC1")
		(10 "In4.Cu" signal "GND1")
		(12 "In5.Cu" signal "IN1")
		(14 "In6.Cu" signal "GND2")
		(16 "In7.Cu" signal "IN2")
		(18 "In8.Cu" signal "GND3")
		(20 "In9.Cu" signal "IN3")
		(22 "In10.Cu" signal "GND4")
		(24 "In11.Cu" signal "IN4")
		(26 "In12.Cu" signal "GND5")
		(28 "In13.Cu" signal "IN5")
		(30 "In14.Cu" signal "GND6")
		(32 "In15.Cu" signal "IN6")
		(34 "In16.Cu" signal "GND7")
		(2 "B.Cu" signal "BOTTOM")
		(9 "F.Adhes" user "F.Adhesive")
		(11 "B.Adhes" user "B.Adhesive")
		(13 "F.Paste" user "Package Geometry/Pastemask Top")
		(15 "B.Paste" user "Package Geometry/Pastemask Bottom")
		(5 "F.SilkS" user "Ref Des/Silkscreen Top")
		(7 "B.SilkS" user "Ref Des/Silkscreen Bottom")
		(1 "F.Mask" user "Board Geometry/Soldermask Top")
		(3 "B.Mask" user "Board Geometry/Soldermask Bottom")
		(17 "Dwgs.User" user "User.Drawings")
		(19 "Cmts.User" user "User.Comments")
		(21 "Eco1.User" user "User.Eco1")
		(23 "Eco2.User" user "User.Eco2")
		(25 "Edge.Cuts" user "Board Geometry/Outline")
		(27 "Margin" user)
		(31 "F.CrtYd" user "Package Geometry/Place Bound Top")
		(29 "B.CrtYd" user "Package Geometry/Place Bound Bottom")
		(35 "F.Fab" user "Ref Des/Assembly Top")
		(33 "B.Fab" user "Ref Des/Assembly Bottom")
	)
	(footprint ""
		(layer "B.Cu")
		(at 388.419086 -294.8051 180)
		(property "Reference" "R3492"
			(at 0 0 0)
			(layer "B.SilkS")
			(hide yes)
			(effects
				(font
					(size 1.27 1.27)
				)
				(justify mirror)
			)
		)
		(property "Value" ""
			(at 0 0 0)
			(layer "B.Fab")
			(effects
				(font
					(size 1.27 1.27)
				)
				(justify mirror)
			)
		)
		(duplicate_pad_numbers_are_jumpers no)
		(fp_line
			(start 0.7874 0.4064)
			(end 0.7874 -0.4064)
			(stroke
				(width 0.1524)
				(type default)
			)
			(layer "B.SilkS")
		)
		(fp_line
			(start 0.7874 -0.4064)
			(end -0.7874 -0.4064)
			(stroke
				(width 0.1524)
				(type default)
			)
			(layer "B.SilkS")
		)
		(fp_line
			(start -0.7874 0.4064)
			(end 0.7874 0.4064)
			(stroke
				(width 0.1524)
				(type default)
			)
			(layer "B.SilkS")
		)
		(fp_line
			(start -0.7874 -0.4064)
			(end -0.7874 0.4064)
			(stroke
				(width 0.1524)
				(type default)
			)
			(layer "B.SilkS")
		)
		(fp_line
			(start 0.67945 0.3048)
			(end 0.67945 -0.305054)
			(stroke
				(width 0.1)
				(type default)
			)
			(layer "B.Fab")
		)
		(fp_line
			(start 0.67945 -0.305054)
			(end 0.12065 -0.305054)
			(stroke
				(width 0.1)
				(type default)
			)
			(layer "B.Fab")
		)
		(fp_line
			(start 0.12065 0.3048)
			(end 0.67945 0.3048)
			(stroke
				(width 0.1)
				(type default)
			)
			(layer "B.Fab")
		)
		(fp_line
			(start 0.12065 0.2794)
			(end 0.12065 0.3048)
			(stroke
				(width 0.1)
				(type default)
			)
			(layer "B.Fab")
		)
		(fp_line
			(start 0.12065 -0.2794)
			(end -0.12065 -0.2794)
			(stroke
				(width 0.1)
				(type default)
			)
			(layer "B.Fab")
		)
		(fp_line
			(start 0.12065 -0.305054)
			(end 0.12065 -0.2794)
			(stroke
				(width 0.1)
				(type default)
			)
			(layer "B.Fab")
		)
		(fp_line
			(start -0.120396 0.3048)
			(end -0.120396 0.2794)
			(stroke
				(width 0.1)
				(type default)
			)
			(layer "B.Fab")
		)
		(fp_line
			(start -0.120396 0.2794)
			(end 0.12065 0.2794)
			(stroke
				(width 0.1)
				(type default)
			)
			(layer "B.Fab")
		)
		(fp_line
			(start -0.12065 -0.2794)
			(end -0.12065 -0.3048)
			(stroke
				(width 0.1)
				(type default)
			)
			(layer "B.Fab")
		)
		(fp_line
			(start -0.12065 -0.3048)
			(end -0.67945 -0.3048)
			(stroke
				(width 0.1)
				(type default)
			)
			(layer "B.Fab")
		)
		(fp_line
			(start -0.67945 0.3048)
			(end -0.120396 0.3048)
			(stroke
				(width 0.1)
				(type default)
			)
			(layer "B.Fab")
		)
		(fp_line
			(start -0.67945 -0.3048)
			(end -0.67945 0.3048)
			(stroke
				(width 0.1)
				(type default)
			)
			(layer "B.Fab")
		)
		(pad "1" smd circle
			(at 0.40005 0)
			(size 0 0)
			(layers "B.Cu" "B.Mask" "B.Paste")
			(net "SPI_PEX3_SDIO2_R")
		)
		(pad "2" smd circle
			(at -0.40005 0)
			(size 0 0)
			(layers "B.Cu" "B.Mask" "B.Paste")
			(net "SPI_PEX3_SDIO2")
		)
	)
	(footprint ""
		(layer "B.Cu")
		(at 63.383414 -108.462318 180)
		(property "Reference" "R81"
			(at 0 0 0)
			(layer "B.SilkS")
			(hide yes)
			(effects
				(font
					(size 1.27 1.27)
				)
				(justify mirror)
			)
		)
		(property "Value" ""
			(at 0 0 0)
			(layer "B.Fab")
			(effects
				(font
					(size 1.27 1.27)
				)
				(justify mirror)
			)
		)
		(duplicate_pad_numbers_are_jumpers no)
		(fp_line
			(start 0.7874 0.4064)
			(end 0.7874 -0.4064)
			(stroke
				(width 0.1524)
				(type default)
			)
			(layer "B.SilkS")
		)
		(fp_line
			(start 0.7874 -0.4064)
			(end -0.7874 -0.4064)
			(stroke
				(width 0.1524)
				(type default)
			)
			(layer "B.SilkS")
		)
		(fp_line
			(start -0.7874 0.4064)
			(end 0.7874 0.4064)
			(stroke
				(width 0.1524)
				(type default)
			)
			(layer "B.SilkS")
		)
		(fp_line
			(start -0.7874 -0.4064)
			(end -0.7874 0.4064)
			(stroke
				(width 0.1524)
				(type default)
			)
			(layer "B.SilkS")
		)
		(fp_line
			(start 0.67945 0.3048)
			(end 0.67945 -0.305054)
			(stroke
				(width 0.1)
				(type default)
			)
			(layer "B.Fab")
		)
		(fp_line
			(start 0.67945 -0.305054)
			(end 0.12065 -0.305054)
			(stroke
				(width 0.1)
				(type default)
			)
			(layer "B.Fab")
		)
		(fp_line
			(start 0.12065 0.3048)
			(end 0.67945 0.3048)
			(stroke
				(width 0.1)
				(type default)
			)
			(layer "B.Fab")
		)
		(fp_line
			(start 0.12065 0.2794)
			(end 0.12065 0.3048)
			(stroke
				(width 0.1)
				(type default)
			)
			(layer "B.Fab")
		)
		(fp_line
			(start 0.12065 -0.2794)
			(end -0.12065 -0.2794)
			(stroke
				(width 0.1)
				(type default)
			)
			(layer "B.Fab")
		)
		(fp_line
			(start 0.12065 -0.305054)
			(end 0.12065 -0.2794)
			(stroke
				(width 0.1)
				(type default)
			)
			(layer "B.Fab")
		)
		(fp_line
			(start -0.120396 0.3048)
			(end -0.120396 0.2794)
			(stroke
				(width 0.1)
				(type default)
			)
			(layer "B.Fab")
		)
		(fp_line
			(start -0.120396 0.2794)
			(end 0.12065 0.2794)
			(stroke
				(width 0.1)
				(type default)
			)
			(layer "B.Fab")
		)
		(fp_line
			(start -0.12065 -0.2794)
			(end -0.12065 -0.3048)
			(stroke
				(width 0.1)
				(type default)
			)
			(layer "B.Fab")
		)
		(fp_line
			(start -0.12065 -0.3048)
			(end -0.67945 -0.3048)
			(stroke
				(width 0.1)
				(type default)
			)
			(layer "B.Fab")
		)
		(fp_line
			(start -0.67945 0.3048)
			(end -0.120396 0.3048)
			(stroke
				(width 0.1)
				(type default)
			)
			(layer "B.Fab")
		)
		(fp_line
			(start -0.67945 -0.3048)
			(end -0.67945 0.3048)
			(stroke
				(width 0.1)
				(type default)
			)
			(layer "B.Fab")
		)
		(pad "1" smd circle
			(at 0.40005 0)
			(size 0 0)
			(layers "B.Cu" "B.Mask" "B.Paste")
			(net "NIC1_BIF0_N")
		)
		(pad "2" smd circle
			(at -0.40005 0)
			(size 0 0)
			(layers "B.Cu" "B.Mask" "B.Paste")
			(net "GND")
		)
	)
	(footprint ""
		(layer "B.Cu")
		(at 405.100028 -290.199826 90)
		(property "Reference" "C1970"
			(at 0 0 90)
			(layer "B.SilkS")
			(hide yes)
			(effects
				(font
					(size 1.27 1.27)
				)
				(justify mirror)
			)
		)
		(property "Value" ""
			(at 0 0 90)
			(layer "B.Fab")
			(effects
				(font
					(size 1.27 1.27)
				)
				(justify mirror)
			)
		)
		(duplicate_pad_numbers_are_jumpers no)
		(fp_line
			(start 0.299974 -0.150114)
			(end -0.299974 -0.150114)
			(stroke
				(width 0.1)
				(type default)
			)
			(layer "B.Fab")
		)
		(fp_line
			(start -0.299974 -0.150114)
			(end -0.299974 0.150114)
			(stroke
				(width 0.1)
				(type default)
			)
			(layer "B.Fab")
		)
		(fp_line
			(start 0.299974 0.150114)
			(end 0.299974 -0.150114)
			(stroke
				(width 0.1)
				(type default)
			)
			(layer "B.Fab")
		)
		(fp_line
			(start -0.299974 0.150114)
			(end 0.299974 0.150114)
			(stroke
				(width 0.1)
				(type default)
			)
			(layer "B.Fab")
		)
		(pad "1" smd rect
			(at 0.2667 0 270)
			(size 0.3048 0.381)
			(layers "B.Cu" "B.Mask" "B.Paste")
			(net "P0V8_SERDES_VDDA_PEX3")
		)
		(pad "2" smd rect
			(at -0.2667 0 270)
			(size 0.3048 0.381)
			(layers "B.Cu" "B.Mask" "B.Paste")
			(net "GND")
		)
	)
	(footprint ""
		(layer "B.Cu")
		(at 338.893912 -222.78721 -90)
		(property "Reference" "C2086"
			(at 0 0 90)
			(layer "B.SilkS")
			(hide yes)
			(effects
				(font
					(size 1.27 1.27)
				)
				(justify mirror)
			)
		)
		(property "Value" ""
			(at 0 0 90)
			(layer "B.Fab")
			(effects
				(font
					(size 1.27 1.27)
				)
				(justify mirror)
			)
		)
		(duplicate_pad_numbers_are_jumpers no)
		(fp_line
			(start -0.69215 0.2921)
			(end 0.69215 0.2921)
			(stroke
				(width 0.1524)
				(type default)
			)
			(layer "B.SilkS")
		)
		(fp_line
			(start 0.69215 0.2921)
			(end 0.69215 -0.2921)
			(stroke
				(width 0.1524)
				(type default)
			)
			(layer "B.SilkS")
		)
		(fp_line
			(start -0.69215 -0.2921)
			(end -0.69215 0.2921)
			(stroke
				(width 0.1524)
				(type default)
			)
			(layer "B.SilkS")
		)
		(fp_line
			(start 0.69215 -0.2921)
			(end -0.69215 -0.2921)
			(stroke
				(width 0.1524)
				(type default)
			)
			(layer "B.SilkS")
		)
		(fp_line
			(start -0.51435 0.2794)
			(end 0.51435 0.2794)
			(stroke
				(width 0.1)
				(type default)
			)
			(layer "B.Fab")
		)
		(fp_line
			(start 0.51435 0.2794)
			(end 0.51435 -0.2794)
			(stroke
				(width 0.1)
				(type default)
			)
			(layer "B.Fab")
		)
		(fp_line
			(start -0.51435 -0.2794)
			(end -0.51435 0.2794)
			(stroke
				(width 0.1)
				(type default)
			)
			(layer "B.Fab")
		)
		(fp_line
			(start 0.51435 -0.2794)
			(end -0.51435 -0.2794)
			(stroke
				(width 0.1)
				(type default)
			)
			(layer "B.Fab")
		)
		(pad "1" smd circle
			(at 0.40005 0 90)
			(size 0 0)
			(layers "B.Cu" "B.Mask" "B.Paste")
			(net "P3V3_FPGA_VCCIO5")
		)
		(pad "2" smd circle
			(at -0.40005 0 90)
			(size 0 0)
			(layers "B.Cu" "B.Mask" "B.Paste")
			(net "GND")
		)
		(zone
			(layer "B.Cu")
			(hatch none 0.5)
			(connect_pads
				(clearance 0)
			)
			(min_thickness 0.25)
			(keepout
				(tracks not_allowed)
				(vias allowed)
				(pads allowed)
				(copperpour not_allowed)
				(footprints allowed)
			)
			(placement
				(enabled no)
				(sheetname "")
			)
			(fill
				(thermal_gap 0.5)
				(thermal_bridge_width 0.5)
				(island_removal_mode 0)
			)
			(polygon
				(pts
					(xy 338.806282 -222.59671) (xy 338.748116 -222.68815) (xy 338.748116 -222.88754) (xy 338.806282 -222.97771)
					(xy 338.981542 -222.97771) (xy 339.039962 -222.88754) (xy 339.039962 -222.68815) (xy 338.981796 -222.59671)
				)
			)
		)
	)
	(footprint ""
		(layer "B.Cu")
		(at 47.77486 -295.3766 90)
		(property "Reference" "C3040"
			(at 0 0 90)
			(layer "B.SilkS")
			(hide yes)
			(effects
				(font
					(size 1.27 1.27)
				)
				(justify mirror)
			)
		)
		(property "Value" ""
			(at 0 0 90)
			(layer "B.Fab")
			(effects
				(font
					(size 1.27 1.27)
				)
				(justify mirror)
			)
		)
		(duplicate_pad_numbers_are_jumpers no)
		(fp_line
			(start 0.299974 -0.150114)
			(end -0.299974 -0.150114)
			(stroke
				(width 0.1)
				(type default)
			)
			(layer "B.Fab")
		)
		(fp_line
			(start -0.299974 -0.150114)
			(end -0.299974 0.150114)
			(stroke
				(width 0.1)
				(type default)
			)
			(layer "B.Fab")
		)
		(fp_line
			(start 0.299974 0.150114)
			(end 0.299974 -0.150114)
			(stroke
				(width 0.1)
				(type default)
			)
			(layer "B.Fab")
		)
		(fp_line
			(start -0.299974 0.150114)
			(end 0.299974 0.150114)
			(stroke
				(width 0.1)
				(type default)
			)
			(layer "B.Fab")
		)
		(pad "1" smd rect
			(at 0.2667 0 270)
			(size 0.3048 0.381)
			(layers "B.Cu" "B.Mask" "B.Paste")
			(net "PCEPLL3_VDDA18_PEX0")
		)
		(pad "2" smd rect
			(at -0.2667 0 270)
			(size 0.3048 0.381)
			(layers "B.Cu" "B.Mask" "B.Paste")
			(net "GND")
		)
	)
	(footprint ""
		(layer "B.Cu")
		(at 11.1379 -264.508234 180)
		(property "Reference" "L85"
			(at 0 0 0)
			(layer "B.SilkS")
			(hide yes)
			(effects
				(font
					(size 1.27 1.27)
				)
				(justify mirror)
			)
		)
		(property "Value" ""
			(at 0 0 0)
			(layer "B.Fab")
			(effects
				(font
					(size 1.27 1.27)
				)
				(justify mirror)
			)
		)
		(duplicate_pad_numbers_are_jumpers no)
		(fp_line
			(start 2.248154 4.9911)
			(end -2.248154 4.9911)
			(stroke
				(width 0.1524)
				(type default)
			)
			(layer "B.SilkS")
		)
		(fp_line
			(start 2.248154 2.156206)
			(end 2.248154 4.9911)
			(stroke
				(width 0.1524)
				(type default)
			)
			(layer "B.SilkS")
		)
		(fp_line
			(start 2.248154 -4.9911)
			(end 2.248154 -2.126488)
			(stroke
				(width 0.1524)
				(type default)
			)
			(layer "B.SilkS")
		)
		(fp_line
			(start -2.248154 4.9911)
			(end -2.248154 2.156206)
			(stroke
				(width 0.1524)
				(type default)
			)
			(layer "B.SilkS")
		)
		(fp_line
			(start -2.248154 -2.126488)
			(end -2.248154 -4.9911)
			(stroke
				(width 0.1524)
				(type default)
			)
			(layer "B.SilkS")
		)
		(fp_line
			(start -2.248154 -4.9911)
			(end 2.248154 -4.9911)
			(stroke
				(width 0.1524)
				(type default)
			)
			(layer "B.SilkS")
		)
		(fp_line
			(start 1.700022 0.899922)
			(end -1.700022 0.899922)
			(stroke
				(width 0.1)
				(type default)
			)
			(layer "B.Fab")
		)
		(fp_line
			(start 1.700022 -0.899922)
			(end 1.700022 0.899922)
			(stroke
				(width 0.1)
				(type default)
			)
			(layer "B.Fab")
		)
		(fp_line
			(start -1.700022 0.899922)
			(end -1.700022 -0.899922)
			(stroke
				(width 0.1)
				(type default)
			)
			(layer "B.Fab")
		)
		(fp_line
			(start -1.700022 -0.899922)
			(end 1.700022 -0.899922)
			(stroke
				(width 0.1)
				(type default)
			)
			(layer "B.Fab")
		)
		(pad "1" smd rect
			(at 1.575054 0)
			(size 1.1684 9.8044)
			(layers "B.Cu" "B.Mask" "B.Paste")
			(net "P1V25_PEX0")
		)
		(pad "2" smd rect
			(at -1.575054 0)
			(size 1.1684 9.8044)
			(layers "B.Cu" "B.Mask" "B.Paste")
			(net "P1V25_SERDES_VDDPLL_PEX0")
		)
	)
	(footprint ""
		(layer "B.Cu")
		(at 230.66756 -221.904052 90)
		(property "Reference" "C3622"
			(at 0 0 90)
			(layer "B.SilkS")
			(hide yes)
			(effects
				(font
					(size 1.27 1.27)
				)
				(justify mirror)
			)
		)
		(property "Value" ""
			(at 0 0 90)
			(layer "B.Fab")
			(effects
				(font
					(size 1.27 1.27)
				)
				(justify mirror)
			)
		)
		(duplicate_pad_numbers_are_jumpers no)
		(fp_line
			(start 0.69215 -0.2921)
			(end -0.69215 -0.2921)
			(stroke
				(width 0.1524)
				(type default)
			)
			(layer "B.SilkS")
		)
		(fp_line
			(start -0.69215 -0.2921)
			(end -0.69215 0.2921)
			(stroke
				(width 0.1524)
				(type default)
			)
			(layer "B.SilkS")
		)
		(fp_line
			(start 0.69215 0.2921)
			(end 0.69215 -0.2921)
			(stroke
				(width 0.1524)
				(type default)
			)
			(layer "B.SilkS")
		)
		(fp_line
			(start -0.69215 0.2921)
			(end 0.69215 0.2921)
			(stroke
				(width 0.1524)
				(type default)
			)
			(layer "B.SilkS")
		)
		(fp_line
			(start 0.51435 -0.2794)
			(end -0.51435 -0.2794)
			(stroke
				(width 0.1)
				(type default)
			)
			(layer "B.Fab")
		)
		(fp_line
			(start -0.51435 -0.2794)
			(end -0.51435 0.2794)
			(stroke
				(width 0.1)
				(type default)
			)
			(layer "B.Fab")
		)
		(fp_line
			(start 0.51435 0.2794)
			(end 0.51435 -0.2794)
			(stroke
				(width 0.1)
				(type default)
			)
			(layer "B.Fab")
		)
		(fp_line
			(start -0.51435 0.2794)
			(end 0.51435 0.2794)
			(stroke
				(width 0.1)
				(type default)
			)
			(layer "B.Fab")
		)
		(pad "1" smd circle
			(at 0.40005 0 270)
			(size 0 0)
			(layers "B.Cu" "B.Mask" "B.Paste")
			(net "P3V3_AUX")
		)
		(pad "2" smd circle
			(at -0.40005 0 270)
			(size 0 0)
			(layers "B.Cu" "B.Mask" "B.Paste")
			(net "GND")
		)
		(zone
			(layer "B.Cu")
			(hatch none 0.5)
			(connect_pads
				(clearance 0)
			)
			(min_thickness 0.25)
			(keepout
				(tracks not_allowed)
				(vias allowed)
				(pads allowed)
				(copperpour not_allowed)
				(footprints allowed)
			)
			(placement
				(enabled no)
				(sheetname "")
			)
			(fill
				(thermal_gap 0.5)
				(thermal_bridge_width 0.5)
				(island_removal_mode 0)
			)
			(polygon
				(pts
					(xy 230.75519 -222.094552) (xy 230.813356 -222.003112) (xy 230.813356 -221.803722) (xy 230.75519 -221.713552)
					(xy 230.57993 -221.713552) (xy 230.52151 -221.803722) (xy 230.52151 -222.003112) (xy 230.579676 -222.094552)
				)
			)
		)
	)
	(footprint ""
		(layer "B.Cu")
		(at 284.249876 -292.099746 90)
		(property "Reference" "C1697"
			(at 0 0 90)
			(layer "B.SilkS")
			(hide yes)
			(effects
				(font
					(size 1.27 1.27)
				)
				(justify mirror)
			)
		)
		(property "Value" ""
			(at 0 0 90)
			(layer "B.Fab")
			(effects
				(font
					(size 1.27 1.27)
				)
				(justify mirror)
			)
		)
		(duplicate_pad_numbers_are_jumpers no)
		(fp_line
			(start 0.299974 -0.150114)
			(end -0.299974 -0.150114)
			(stroke
				(width 0.1)
				(type default)
			)
			(layer "B.Fab")
		)
		(fp_line
			(start -0.299974 -0.150114)
			(end -0.299974 0.150114)
			(stroke
				(width 0.1)
				(type default)
			)
			(layer "B.Fab")
		)
		(fp_line
			(start 0.299974 0.150114)
			(end 0.299974 -0.150114)
			(stroke
				(width 0.1)
				(type default)
			)
			(layer "B.Fab")
		)
		(fp_line
			(start -0.299974 0.150114)
			(end 0.299974 0.150114)
			(stroke
				(width 0.1)
				(type default)
			)
			(layer "B.Fab")
		)
		(pad "1" smd rect
			(at 0.2667 0 270)
			(size 0.3048 0.381)
			(layers "B.Cu" "B.Mask" "B.Paste")
			(net "P0V8_SERDES_VDDA_PEX2")
		)
		(pad "2" smd rect
			(at -0.2667 0 270)
			(size 0.3048 0.381)
			(layers "B.Cu" "B.Mask" "B.Paste")
			(net "GND")
		)
	)
	(footprint ""
		(layer "B.Cu")
		(at 295.174924 -297.79976 -90)
		(property "Reference" "C1648"
			(at 0 0 90)
			(layer "B.SilkS")
			(hide yes)
			(effects
				(font
					(size 1.27 1.27)
				)
				(justify mirror)
			)
		)
		(property "Value" ""
			(at 0 0 90)
			(layer "B.Fab")
			(effects
				(font
					(size 1.27 1.27)
				)
				(justify mirror)
			)
		)
		(duplicate_pad_numbers_are_jumpers no)
		(fp_line
			(start -0.299974 0.150114)
			(end 0.299974 0.150114)
			(stroke
				(width 0.1)
				(type default)
			)
			(layer "B.Fab")
		)
		(fp_line
			(start 0.299974 0.150114)
			(end 0.299974 -0.150114)
			(stroke
				(width 0.1)
				(type default)
			)
			(layer "B.Fab")
		)
		(fp_line
			(start -0.299974 -0.150114)
			(end -0.299974 0.150114)
			(stroke
				(width 0.1)
				(type default)
			)
			(layer "B.Fab")
		)
		(fp_line
			(start 0.299974 -0.150114)
			(end -0.299974 -0.150114)
			(stroke
				(width 0.1)
				(type default)
			)
			(layer "B.Fab")
		)
		(pad "1" smd rect
			(at 0.2667 0 90)
			(size 0.3048 0.381)
			(layers "B.Cu" "B.Mask" "B.Paste")
			(net "P0V8_PEX2")
		)
		(pad "2" smd rect
			(at -0.2667 0 90)
			(size 0.3048 0.381)
			(layers "B.Cu" "B.Mask" "B.Paste")
			(net "GND")
		)
	)
)
